FILE_TYPE = CONNECTIVITY;
{Allegro Design Entry HDL 16.6-p007 (v16-6-112F) 10/10/2012}
"PAGE_NUMBER" = 263;
0"NC";
END.
